(kicad_pcb
	(version 20241229)
	(generator "pcbnew")
	(generator_version "9.0")
	(general
		(thickness 1.599998)
		(legacy_teardrops no)
	)
	(paper "A4")
	(title_block
		(title "Artix - Datacenter Secure Control Module (DC-SCM)")
		(date "2024-11-06")
		(rev "1.1.3")
		(comment 9 "footprints 436-442 of 544")
	)
	(layers
		(0 "F.Cu" signal)
		(4 "In1.Cu" signal)
		(6 "In2.Cu" signal)
		(8 "In3.Cu" signal)
		(10 "In4.Cu" signal)
		(12 "In5.Cu" signal)
		(14 "In6.Cu" signal)
		(2 "B.Cu" signal)
		(9 "F.Adhes" user "F.Adhesive")
		(11 "B.Adhes" user "B.Adhesive")
		(13 "F.Paste" user)
		(15 "B.Paste" user)
		(5 "F.SilkS" user "F.Silkscreen")
		(7 "B.SilkS" user "B.Silkscreen")
		(1 "F.Mask" user)
		(3 "B.Mask" user)
		(17 "Dwgs.User" user "User.Drawings")
		(19 "Cmts.User" user "User.Comments")
		(21 "Eco1.User" user "User.Eco1")
		(23 "Eco2.User" user "User.Eco2")
		(25 "Edge.Cuts" user)
		(27 "Margin" user)
		(31 "F.CrtYd" user "F.Courtyard")
		(29 "B.CrtYd" user "B.Courtyard")
		(35 "F.Fab" user)
		(33 "B.Fab" user)
	)
	(footprint "antmicro-footprints:R_0402_1005Metric"
		(layer "B.Cu")
		(at 143.069 120.927 180)
		(descr "Resistor SMD 0402")
		(tags "resistor SMD 0402")
		(property "Reference" "R120"
			(at -3.731 -0.373 0)
			(layer "B.SilkS")
			(effects
				(font
					(size 0.7 0.7)
					(thickness 0.15)
				)
				(justify left bottom mirror)
			)
		)
		(property "Value" "R_47k_0402"
			(at 0 -1.4 0)
			(layer "B.Fab")
			(effects
				(font
					(size 0.7 0.7)
					(thickness 0.15)
				)
				(justify left bottom mirror)
			)
		)
		(property "Datasheet" "https://www.bourns.com/docs/product-datasheets/cr.pdf"
			(at 0 0 180)
			(layer "F.Fab")
			(hide yes)
			(effects
				(font
					(size 1.27 1.27)
					(thickness 0.15)
				)
			)
		)
		(property "Description" "SMD Chip Resistor, 47 kohm, ± 1%, 62.5 mW, 0402 [1005 Metric], Thick Film, General Purpose"
			(at 0 0 180)
			(layer "F.Fab")
			(hide yes)
			(effects
				(font
					(size 1.27 1.27)
					(thickness 0.15)
				)
			)
		)
		(property "Author" "Antmicro"
			(at 286.138 241.854 0)
			(layer "B.Fab")
			(hide yes)
			(effects
				(font
					(size 1 1)
					(thickness 0.15)
				)
				(justify mirror)
			)
		)
		(property "License" "Apache-2.0"
			(at 286.138 241.854 0)
			(layer "B.Fab")
			(hide yes)
			(effects
				(font
					(size 1 1)
					(thickness 0.15)
				)
				(justify mirror)
			)
		)
		(property "MPN" "CR0402-FX-4702GLF"
			(at 286.138 241.854 0)
			(layer "B.Fab")
			(hide yes)
			(effects
				(font
					(size 1 1)
					(thickness 0.15)
				)
				(justify mirror)
			)
		)
		(property "Manufacturer" "Bourns"
			(at 286.138 241.854 0)
			(layer "B.Fab")
			(hide yes)
			(effects
				(font
					(size 1 1)
					(thickness 0.15)
				)
				(justify mirror)
			)
		)
		(property "Tolerance" "1%"
			(at 286.138 241.854 0)
			(layer "B.Fab")
			(hide yes)
			(effects
				(font
					(size 1 1)
					(thickness 0.15)
				)
				(justify mirror)
			)
		)
		(property "Val" "47k"
			(at 286.138 241.854 0)
			(layer "B.Fab")
			(hide yes)
			(effects
				(font
					(size 1 1)
					(thickness 0.15)
				)
				(justify mirror)
			)
		)
		(sheetname "/Interfaces/")
		(sheetfile "interfaces.kicad_sch")
		(attr smd)
		(fp_rect
			(start -0.925 0.47)
			(end 0.925 -0.47)
			(stroke
				(width 0.05)
				(type default)
			)
			(fill no)
			(layer "B.CrtYd")
		)
		(fp_rect
			(start -0.5 0.25)
			(end 0.5 -0.25)
			(stroke
				(width 0.15)
				(type solid)
			)
			(fill no)
			(layer "B.Fab")
		)
		(pad "1" smd roundrect
			(at -0.48 0 180)
			(size 0.59 0.64)
			(layers "B.Cu" "B.Mask" "B.Paste")
			(roundrect_rratio 0.25)
			(net 2 "VCC3V3")
			(pintype "passive")
		)
		(pad "2" smd roundrect
			(at 0.48 0 180)
			(size 0.59 0.64)
			(layers "B.Cu" "B.Mask" "B.Paste")
			(roundrect_rratio 0.25)
			(net 322 "MMC_DAT1")
			(pintype "passive")
		)
	)
	(footprint "antmicro-footprints:R_0402_1005Metric"
		(layer "B.Cu")
		(at 140.274 124.214)
		(descr "Resistor SMD 0402")
		(tags "resistor SMD 0402")
		(property "Reference" "R121"
			(at -0.674 -0.614 0)
			(layer "B.SilkS")
			(effects
				(font
					(size 0.7 0.7)
					(thickness 0.15)
				)
				(justify right bottom mirror)
			)
		)
		(property "Value" "R_47k_0402"
			(at 0 -1.4 0)
			(layer "B.Fab")
			(effects
				(font
					(size 0.7 0.7)
					(thickness 0.15)
				)
				(justify right bottom mirror)
			)
		)
		(property "Datasheet" "https://www.bourns.com/docs/product-datasheets/cr.pdf"
			(at 0 0 0)
			(layer "F.Fab")
			(hide yes)
			(effects
				(font
					(size 1.27 1.27)
					(thickness 0.15)
				)
			)
		)
		(property "Description" "SMD Chip Resistor, 47 kohm, ± 1%, 62.5 mW, 0402 [1005 Metric], Thick Film, General Purpose"
			(at 0 0 0)
			(layer "F.Fab")
			(hide yes)
			(effects
				(font
					(size 1.27 1.27)
					(thickness 0.15)
				)
			)
		)
		(property "Author" "Antmicro"
			(at 0 0 0)
			(layer "B.Fab")
			(hide yes)
			(effects
				(font
					(size 1 1)
					(thickness 0.15)
				)
				(justify mirror)
			)
		)
		(property "License" "Apache-2.0"
			(at 0 0 0)
			(layer "B.Fab")
			(hide yes)
			(effects
				(font
					(size 1 1)
					(thickness 0.15)
				)
				(justify mirror)
			)
		)
		(property "MPN" "CR0402-FX-4702GLF"
			(at 0 0 0)
			(layer "B.Fab")
			(hide yes)
			(effects
				(font
					(size 1 1)
					(thickness 0.15)
				)
				(justify mirror)
			)
		)
		(property "Manufacturer" "Bourns"
			(at 0 0 0)
			(layer "B.Fab")
			(hide yes)
			(effects
				(font
					(size 1 1)
					(thickness 0.15)
				)
				(justify mirror)
			)
		)
		(property "Tolerance" "1%"
			(at 0 0 0)
			(layer "B.Fab")
			(hide yes)
			(effects
				(font
					(size 1 1)
					(thickness 0.15)
				)
				(justify mirror)
			)
		)
		(property "Val" "47k"
			(at 0 0 0)
			(layer "B.Fab")
			(hide yes)
			(effects
				(font
					(size 1 1)
					(thickness 0.15)
				)
				(justify mirror)
			)
		)
		(sheetname "/Interfaces/")
		(sheetfile "interfaces.kicad_sch")
		(attr smd)
		(fp_rect
			(start -0.925 0.47)
			(end 0.925 -0.47)
			(stroke
				(width 0.05)
				(type default)
			)
			(fill no)
			(layer "B.CrtYd")
		)
		(fp_rect
			(start -0.5 0.25)
			(end 0.5 -0.25)
			(stroke
				(width 0.15)
				(type solid)
			)
			(fill no)
			(layer "B.Fab")
		)
		(pad "1" smd roundrect
			(at -0.48 0)
			(size 0.59 0.64)
			(layers "B.Cu" "B.Mask" "B.Paste")
			(roundrect_rratio 0.25)
			(net 2 "VCC3V3")
			(pintype "passive")
		)
		(pad "2" smd roundrect
			(at 0.48 0)
			(size 0.59 0.64)
			(layers "B.Cu" "B.Mask" "B.Paste")
			(roundrect_rratio 0.25)
			(net 323 "MMC_DAT2")
			(pintype "passive")
		)
	)
	(footprint "antmicro-footprints:R_0402_1005Metric"
		(layer "B.Cu")
		(at 140.919 121.027)
		(descr "Resistor SMD 0402")
		(tags "resistor SMD 0402")
		(property "Reference" "R122"
			(at -0.019 -0.627 0)
			(layer "B.SilkS")
			(effects
				(font
					(size 0.7 0.7)
					(thickness 0.15)
				)
				(justify right bottom mirror)
			)
		)
		(property "Value" "R_47k_0402"
			(at 0 -1.4 0)
			(layer "B.Fab")
			(effects
				(font
					(size 0.7 0.7)
					(thickness 0.15)
				)
				(justify right bottom mirror)
			)
		)
		(property "Datasheet" "https://www.bourns.com/docs/product-datasheets/cr.pdf"
			(at 0 0 0)
			(layer "F.Fab")
			(hide yes)
			(effects
				(font
					(size 1.27 1.27)
					(thickness 0.15)
				)
			)
		)
		(property "Description" "SMD Chip Resistor, 47 kohm, ± 1%, 62.5 mW, 0402 [1005 Metric], Thick Film, General Purpose"
			(at 0 0 0)
			(layer "F.Fab")
			(hide yes)
			(effects
				(font
					(size 1.27 1.27)
					(thickness 0.15)
				)
			)
		)
		(property "Author" "Antmicro"
			(at 0 0 0)
			(layer "B.Fab")
			(hide yes)
			(effects
				(font
					(size 1 1)
					(thickness 0.15)
				)
				(justify mirror)
			)
		)
		(property "License" "Apache-2.0"
			(at 0 0 0)
			(layer "B.Fab")
			(hide yes)
			(effects
				(font
					(size 1 1)
					(thickness 0.15)
				)
				(justify mirror)
			)
		)
		(property "MPN" "CR0402-FX-4702GLF"
			(at 0 0 0)
			(layer "B.Fab")
			(hide yes)
			(effects
				(font
					(size 1 1)
					(thickness 0.15)
				)
				(justify mirror)
			)
		)
		(property "Manufacturer" "Bourns"
			(at 0 0 0)
			(layer "B.Fab")
			(hide yes)
			(effects
				(font
					(size 1 1)
					(thickness 0.15)
				)
				(justify mirror)
			)
		)
		(property "Tolerance" "1%"
			(at 0 0 0)
			(layer "B.Fab")
			(hide yes)
			(effects
				(font
					(size 1 1)
					(thickness 0.15)
				)
				(justify mirror)
			)
		)
		(property "Val" "47k"
			(at 0 0 0)
			(layer "B.Fab")
			(hide yes)
			(effects
				(font
					(size 1 1)
					(thickness 0.15)
				)
				(justify mirror)
			)
		)
		(sheetname "/Interfaces/")
		(sheetfile "interfaces.kicad_sch")
		(attr smd)
		(fp_rect
			(start -0.925 0.47)
			(end 0.925 -0.47)
			(stroke
				(width 0.05)
				(type default)
			)
			(fill no)
			(layer "B.CrtYd")
		)
		(fp_rect
			(start -0.5 0.25)
			(end 0.5 -0.25)
			(stroke
				(width 0.15)
				(type solid)
			)
			(fill no)
			(layer "B.Fab")
		)
		(pad "1" smd roundrect
			(at -0.48 0)
			(size 0.59 0.64)
			(layers "B.Cu" "B.Mask" "B.Paste")
			(roundrect_rratio 0.25)
			(net 2 "VCC3V3")
			(pintype "passive")
		)
		(pad "2" smd roundrect
			(at 0.48 0)
			(size 0.59 0.64)
			(layers "B.Cu" "B.Mask" "B.Paste")
			(roundrect_rratio 0.25)
			(net 324 "MMC_DAT3")
			(pintype "passive")
		)
	)
	(footprint "antmicro-footprints:R_0402_1005Metric"
		(layer "B.Cu")
		(at 136.774 121.024 180)
		(descr "Resistor SMD 0402")
		(tags "resistor SMD 0402")
		(property "Reference" "R123"
			(at -1.126 0.524 0)
			(layer "B.SilkS")
			(effects
				(font
					(size 0.7 0.7)
					(thickness 0.15)
				)
				(justify left bottom mirror)
			)
		)
		(property "Value" "R_47k_0402"
			(at 0 -1.4 0)
			(layer "B.Fab")
			(effects
				(font
					(size 0.7 0.7)
					(thickness 0.15)
				)
				(justify left bottom mirror)
			)
		)
		(property "Datasheet" "https://www.bourns.com/docs/product-datasheets/cr.pdf"
			(at 0 0 180)
			(layer "F.Fab")
			(hide yes)
			(effects
				(font
					(size 1.27 1.27)
					(thickness 0.15)
				)
			)
		)
		(property "Description" "SMD Chip Resistor, 47 kohm, ± 1%, 62.5 mW, 0402 [1005 Metric], Thick Film, General Purpose"
			(at 0 0 180)
			(layer "F.Fab")
			(hide yes)
			(effects
				(font
					(size 1.27 1.27)
					(thickness 0.15)
				)
			)
		)
		(property "Author" "Antmicro"
			(at 273.548 242.048 0)
			(layer "B.Fab")
			(hide yes)
			(effects
				(font
					(size 1 1)
					(thickness 0.15)
				)
				(justify mirror)
			)
		)
		(property "License" "Apache-2.0"
			(at 273.548 242.048 0)
			(layer "B.Fab")
			(hide yes)
			(effects
				(font
					(size 1 1)
					(thickness 0.15)
				)
				(justify mirror)
			)
		)
		(property "MPN" "CR0402-FX-4702GLF"
			(at 273.548 242.048 0)
			(layer "B.Fab")
			(hide yes)
			(effects
				(font
					(size 1 1)
					(thickness 0.15)
				)
				(justify mirror)
			)
		)
		(property "Manufacturer" "Bourns"
			(at 273.548 242.048 0)
			(layer "B.Fab")
			(hide yes)
			(effects
				(font
					(size 1 1)
					(thickness 0.15)
				)
				(justify mirror)
			)
		)
		(property "Tolerance" "1%"
			(at 273.548 242.048 0)
			(layer "B.Fab")
			(hide yes)
			(effects
				(font
					(size 1 1)
					(thickness 0.15)
				)
				(justify mirror)
			)
		)
		(property "Val" "47k"
			(at 273.548 242.048 0)
			(layer "B.Fab")
			(hide yes)
			(effects
				(font
					(size 1 1)
					(thickness 0.15)
				)
				(justify mirror)
			)
		)
		(sheetname "/Interfaces/")
		(sheetfile "interfaces.kicad_sch")
		(attr smd)
		(fp_rect
			(start -0.925 0.47)
			(end 0.925 -0.47)
			(stroke
				(width 0.05)
				(type default)
			)
			(fill no)
			(layer "B.CrtYd")
		)
		(fp_rect
			(start -0.5 0.25)
			(end 0.5 -0.25)
			(stroke
				(width 0.15)
				(type solid)
			)
			(fill no)
			(layer "B.Fab")
		)
		(pad "1" smd roundrect
			(at -0.48 0 180)
			(size 0.59 0.64)
			(layers "B.Cu" "B.Mask" "B.Paste")
			(roundrect_rratio 0.25)
			(net 2 "VCC3V3")
			(pintype "passive")
		)
		(pad "2" smd roundrect
			(at 0.48 0 180)
			(size 0.59 0.64)
			(layers "B.Cu" "B.Mask" "B.Paste")
			(roundrect_rratio 0.25)
			(net 325 "MMC_DAT4")
			(pintype "passive")
		)
	)
	(footprint "antmicro-footprints:R_0402_1005Metric"
		(layer "B.Cu")
		(at 136.274 124.214 180)
		(descr "Resistor SMD 0402")
		(tags "resistor SMD 0402")
		(property "Reference" "R124"
			(at -1.926 -1.286 0)
			(layer "B.SilkS")
			(effects
				(font
					(size 0.7 0.7)
					(thickness 0.15)
				)
				(justify left bottom mirror)
			)
		)
		(property "Value" "R_47k_0402"
			(at 0 -1.4 0)
			(layer "B.Fab")
			(effects
				(font
					(size 0.7 0.7)
					(thickness 0.15)
				)
				(justify left bottom mirror)
			)
		)
		(property "Datasheet" "https://www.bourns.com/docs/product-datasheets/cr.pdf"
			(at 0 0 180)
			(layer "F.Fab")
			(hide yes)
			(effects
				(font
					(size 1.27 1.27)
					(thickness 0.15)
				)
			)
		)
		(property "Description" "SMD Chip Resistor, 47 kohm, ± 1%, 62.5 mW, 0402 [1005 Metric], Thick Film, General Purpose"
			(at 0 0 180)
			(layer "F.Fab")
			(hide yes)
			(effects
				(font
					(size 1.27 1.27)
					(thickness 0.15)
				)
			)
		)
		(property "Author" "Antmicro"
			(at 272.548 248.428 0)
			(layer "B.Fab")
			(hide yes)
			(effects
				(font
					(size 1 1)
					(thickness 0.15)
				)
				(justify mirror)
			)
		)
		(property "License" "Apache-2.0"
			(at 272.548 248.428 0)
			(layer "B.Fab")
			(hide yes)
			(effects
				(font
					(size 1 1)
					(thickness 0.15)
				)
				(justify mirror)
			)
		)
		(property "MPN" "CR0402-FX-4702GLF"
			(at 272.548 248.428 0)
			(layer "B.Fab")
			(hide yes)
			(effects
				(font
					(size 1 1)
					(thickness 0.15)
				)
				(justify mirror)
			)
		)
		(property "Manufacturer" "Bourns"
			(at 272.548 248.428 0)
			(layer "B.Fab")
			(hide yes)
			(effects
				(font
					(size 1 1)
					(thickness 0.15)
				)
				(justify mirror)
			)
		)
		(property "Tolerance" "1%"
			(at 272.548 248.428 0)
			(layer "B.Fab")
			(hide yes)
			(effects
				(font
					(size 1 1)
					(thickness 0.15)
				)
				(justify mirror)
			)
		)
		(property "Val" "47k"
			(at 272.548 248.428 0)
			(layer "B.Fab")
			(hide yes)
			(effects
				(font
					(size 1 1)
					(thickness 0.15)
				)
				(justify mirror)
			)
		)
		(sheetname "/Interfaces/")
		(sheetfile "interfaces.kicad_sch")
		(attr smd)
		(fp_rect
			(start -0.925 0.47)
			(end 0.925 -0.47)
			(stroke
				(width 0.05)
				(type default)
			)
			(fill no)
			(layer "B.CrtYd")
		)
		(fp_rect
			(start -0.5 0.25)
			(end 0.5 -0.25)
			(stroke
				(width 0.15)
				(type solid)
			)
			(fill no)
			(layer "B.Fab")
		)
		(pad "1" smd roundrect
			(at -0.48 0 180)
			(size 0.59 0.64)
			(layers "B.Cu" "B.Mask" "B.Paste")
			(roundrect_rratio 0.25)
			(net 2 "VCC3V3")
			(pintype "passive")
		)
		(pad "2" smd roundrect
			(at 0.48 0 180)
			(size 0.59 0.64)
			(layers "B.Cu" "B.Mask" "B.Paste")
			(roundrect_rratio 0.25)
			(net 326 "MMC_DAT5")
			(pintype "passive")
		)
	)
	(footprint "antmicro-footprints:R_0402_1005Metric"
		(layer "B.Cu")
		(at 134.319 120.927)
		(descr "Resistor SMD 0402")
		(tags "resistor SMD 0402")
		(property "Reference" "R125"
			(at -3.619 0.373 0)
			(layer "B.SilkS")
			(effects
				(font
					(size 0.7 0.7)
					(thickness 0.15)
				)
				(justify right bottom mirror)
			)
		)
		(property "Value" "R_47k_0402"
			(at 0 -1.4 0)
			(layer "B.Fab")
			(effects
				(font
					(size 0.7 0.7)
					(thickness 0.15)
				)
				(justify right bottom mirror)
			)
		)
		(property "Datasheet" "https://www.bourns.com/docs/product-datasheets/cr.pdf"
			(at 0 0 0)
			(layer "F.Fab")
			(hide yes)
			(effects
				(font
					(size 1.27 1.27)
					(thickness 0.15)
				)
			)
		)
		(property "Description" "SMD Chip Resistor, 47 kohm, ± 1%, 62.5 mW, 0402 [1005 Metric], Thick Film, General Purpose"
			(at 0 0 0)
			(layer "F.Fab")
			(hide yes)
			(effects
				(font
					(size 1.27 1.27)
					(thickness 0.15)
				)
			)
		)
		(property "Author" "Antmicro"
			(at 0 0 0)
			(layer "B.Fab")
			(hide yes)
			(effects
				(font
					(size 1 1)
					(thickness 0.15)
				)
				(justify mirror)
			)
		)
		(property "License" "Apache-2.0"
			(at 0 0 0)
			(layer "B.Fab")
			(hide yes)
			(effects
				(font
					(size 1 1)
					(thickness 0.15)
				)
				(justify mirror)
			)
		)
		(property "MPN" "CR0402-FX-4702GLF"
			(at 0 0 0)
			(layer "B.Fab")
			(hide yes)
			(effects
				(font
					(size 1 1)
					(thickness 0.15)
				)
				(justify mirror)
			)
		)
		(property "Manufacturer" "Bourns"
			(at 0 0 0)
			(layer "B.Fab")
			(hide yes)
			(effects
				(font
					(size 1 1)
					(thickness 0.15)
				)
				(justify mirror)
			)
		)
		(property "Tolerance" "1%"
			(at 0 0 0)
			(layer "B.Fab")
			(hide yes)
			(effects
				(font
					(size 1 1)
					(thickness 0.15)
				)
				(justify mirror)
			)
		)
		(property "Val" "47k"
			(at 0 0 0)
			(layer "B.Fab")
			(hide yes)
			(effects
				(font
					(size 1 1)
					(thickness 0.15)
				)
				(justify mirror)
			)
		)
		(sheetname "/Interfaces/")
		(sheetfile "interfaces.kicad_sch")
		(attr smd)
		(fp_rect
			(start -0.925 0.47)
			(end 0.925 -0.47)
			(stroke
				(width 0.05)
				(type default)
			)
			(fill no)
			(layer "B.CrtYd")
		)
		(fp_rect
			(start -0.5 0.25)
			(end 0.5 -0.25)
			(stroke
				(width 0.15)
				(type solid)
			)
			(fill no)
			(layer "B.Fab")
		)
		(pad "1" smd roundrect
			(at -0.48 0)
			(size 0.59 0.64)
			(layers "B.Cu" "B.Mask" "B.Paste")
			(roundrect_rratio 0.25)
			(net 2 "VCC3V3")
			(pintype "passive")
		)
		(pad "2" smd roundrect
			(at 0.48 0)
			(size 0.59 0.64)
			(layers "B.Cu" "B.Mask" "B.Paste")
			(roundrect_rratio 0.25)
			(net 327 "MMC_DAT6")
			(pintype "passive")
		)
	)
	(footprint "antmicro-footprints:R_0402_1005Metric"
		(layer "B.Cu")
		(at 134.274 124.214)
		(descr "Resistor SMD 0402")
		(tags "resistor SMD 0402")
		(property "Reference" "R126"
			(at -1.874 1.286 0)
			(layer "B.SilkS")
			(effects
				(font
					(size 0.7 0.7)
					(thickness 0.15)
				)
				(justify right bottom mirror)
			)
		)
		(property "Value" "R_47k_0402"
			(at 0 -1.4 0)
			(layer "B.Fab")
			(effects
				(font
					(size 0.7 0.7)
					(thickness 0.15)
				)
				(justify right bottom mirror)
			)
		)
		(property "Datasheet" "https://www.bourns.com/docs/product-datasheets/cr.pdf"
			(at 0 0 0)
			(layer "F.Fab")
			(hide yes)
			(effects
				(font
					(size 1.27 1.27)
					(thickness 0.15)
				)
			)
		)
		(property "Description" "SMD Chip Resistor, 47 kohm, ± 1%, 62.5 mW, 0402 [1005 Metric], Thick Film, General Purpose"
			(at 0 0 0)
			(layer "F.Fab")
			(hide yes)
			(effects
				(font
					(size 1.27 1.27)
					(thickness 0.15)
				)
			)
		)
		(property "Author" "Antmicro"
			(at 0 0 0)
			(layer "B.Fab")
			(hide yes)
			(effects
				(font
					(size 1 1)
					(thickness 0.15)
				)
				(justify mirror)
			)
		)
		(property "License" "Apache-2.0"
			(at 0 0 0)
			(layer "B.Fab")
			(hide yes)
			(effects
				(font
					(size 1 1)
					(thickness 0.15)
				)
				(justify mirror)
			)
		)
		(property "MPN" "CR0402-FX-4702GLF"
			(at 0 0 0)
			(layer "B.Fab")
			(hide yes)
			(effects
				(font
					(size 1 1)
					(thickness 0.15)
				)
				(justify mirror)
			)
		)
		(property "Manufacturer" "Bourns"
			(at 0 0 0)
			(layer "B.Fab")
			(hide yes)
			(effects
				(font
					(size 1 1)
					(thickness 0.15)
				)
				(justify mirror)
			)
		)
		(property "Tolerance" "1%"
			(at 0 0 0)
			(layer "B.Fab")
			(hide yes)
			(effects
				(font
					(size 1 1)
					(thickness 0.15)
				)
				(justify mirror)
			)
		)
		(property "Val" "47k"
			(at 0 0 0)
			(layer "B.Fab")
			(hide yes)
			(effects
				(font
					(size 1 1)
					(thickness 0.15)
				)
				(justify mirror)
			)
		)
		(sheetname "/Interfaces/")
		(sheetfile "interfaces.kicad_sch")
		(attr smd)
		(fp_rect
			(start -0.925 0.47)
			(end 0.925 -0.47)
			(stroke
				(width 0.05)
				(type default)
			)
			(fill no)
			(layer "B.CrtYd")
		)
		(fp_rect
			(start -0.5 0.25)
			(end 0.5 -0.25)
			(stroke
				(width 0.15)
				(type solid)
			)
			(fill no)
			(layer "B.Fab")
		)
		(pad "1" smd roundrect
			(at -0.48 0)
			(size 0.59 0.64)
			(layers "B.Cu" "B.Mask" "B.Paste")
			(roundrect_rratio 0.25)
			(net 2 "VCC3V3")
			(pintype "passive")
		)
		(pad "2" smd roundrect
			(at 0.48 0)
			(size 0.59 0.64)
			(layers "B.Cu" "B.Mask" "B.Paste")
			(roundrect_rratio 0.25)
			(net 328 "MMC_DAT7")
			(pintype "passive")
		)
	)
)
